(kicad_pcb
	(version 20260206)
	(generator "pcbnew")
	(generator_version "10.0")
	(general
		(thickness 1.21888)
		(legacy_teardrops no)
	)
	(paper "A4")
	(title_block
		(title "timecard-v8 — TimeCard-DC-V8_EXP.PcbDoc")
		(comment 1 "Time Appliance Project (Time Card) / footprints 90-96 of 288")
	)
	(layers
		(0 "F.Cu" signal "TOP")
		(4 "In1.Cu" signal "SGND")
		(6 "In2.Cu" signal "IN1")
		(8 "In3.Cu" signal "IN2")
		(10 "In4.Cu" signal "SGND1")
		(2 "B.Cu" signal "BOTTOM")
		(9 "F.Adhes" user "F.Adhesive")
		(11 "B.Adhes" user "B.Adhesive")
		(13 "F.Paste" user "Top Paste")
		(15 "B.Paste" user "Bottom Paste")
		(5 "F.SilkS" user "Top Overlay")
		(7 "B.SilkS" user "Bottom Overlay")
		(1 "F.Mask" user "Top Solder")
		(3 "B.Mask" user "Bottom Solder")
		(17 "Dwgs.User" user "User.Drawings")
		(19 "Cmts.User" user "User.Comments")
		(21 "Eco1.User" user "User.Eco1")
		(23 "Eco2.User" user "User.Eco2")
		(25 "Edge.Cuts" user)
		(27 "Margin" user)
		(31 "F.CrtYd" user "Top Courtyard")
		(29 "B.CrtYd" user "Bottom Courtyard")
		(35 "F.Fab" user "Top Component Center")
		(33 "B.Fab" user "Bottom Component Center")
	)
	(footprint "Vault:FP-RUT0012A-MFG"
		(layer "F.Cu")
		(at 126.2261 85.9162 90)
		(property "Reference" "U23"
			(at -3.126931 -0.3714 0)
			(unlocked yes)
			(layer "F.SilkS")
			(effects
				(font
					(size 0.762 0.762)
					(thickness 0.2286)
				)
			)
		)
		(property "Value" "TMUX1072RUTR"
			(at 7.426665 3.164071 90)
			(unlocked yes)
			(layer "F.SilkS")
			(hide yes)
			(effects
				(font
					(size 0.762 0.762)
					(thickness 0.2286)
				)
			)
		)
		(sheetname "USBUart_DipSelects")
		(sheetfile "USBUart_DipSelects.kicad_sch")
		(duplicate_pad_numbers_are_jumpers no)
		(fp_line
			(start -0.9 -1.525)
			(end 0.9 -1.525)
			(stroke
				(width 0.2)
				(type solid)
			)
			(layer "F.SilkS")
		)
		(fp_line
			(start -0.9 1.525)
			(end 0.9 1.525)
			(stroke
				(width 0.2)
				(type solid)
			)
			(layer "F.SilkS")
		)
		(fp_circle
			(center -1.575 -0.8)
			(end -1.45 -0.8)
			(stroke
				(width 0.25)
				(type solid)
			)
			(fill no)
			(layer "F.SilkS")
		)
		(fp_rect
			(start 0.35 -0.7)
			(end 0.85 -0.9)
			(stroke
				(width 0)
				(type default)
			)
			(fill yes)
			(layer "F.Paste")
		)
		(fp_rect
			(start -0.1 -0.5)
			(end 0.1 -1)
			(stroke
				(width 0)
				(type default)
			)
			(fill yes)
			(layer "F.Paste")
		)
		(fp_rect
			(start 0.35 -0.3)
			(end 0.85 -0.5)
			(stroke
				(width 0)
				(type default)
			)
			(fill yes)
			(layer "F.Paste")
		)
		(fp_rect
			(start -0.85 -0.3)
			(end -0.35 -0.5)
			(stroke
				(width 0)
				(type default)
			)
			(fill yes)
			(layer "F.Paste")
		)
		(fp_rect
			(start 0.35 0.1)
			(end 0.85 -0.1)
			(stroke
				(width 0)
				(type default)
			)
			(fill yes)
			(layer "F.Paste")
		)
		(fp_rect
			(start -0.85 0.1)
			(end -0.35 -0.1)
			(stroke
				(width 0)
				(type default)
			)
			(fill yes)
			(layer "F.Paste")
		)
		(fp_rect
			(start 0.35 0.5)
			(end 0.85 0.3)
			(stroke
				(width 0)
				(type default)
			)
			(fill yes)
			(layer "F.Paste")
		)
		(fp_rect
			(start -0.85 0.5)
			(end -0.35 0.3)
			(stroke
				(width 0)
				(type default)
			)
			(fill yes)
			(layer "F.Paste")
		)
		(fp_rect
			(start 0.349995 0.900005)
			(end 0.850005 0.700005)
			(stroke
				(width 0)
				(type default)
			)
			(fill yes)
			(layer "F.Paste")
		)
		(fp_rect
			(start -0.850005 0.900005)
			(end -0.349995 0.700005)
			(stroke
				(width 0)
				(type default)
			)
			(fill yes)
			(layer "F.Paste")
		)
		(fp_rect
			(start -0.099995 1.000005)
			(end 0.100005 0.499995)
			(stroke
				(width 0)
				(type default)
			)
			(fill yes)
			(layer "F.Paste")
		)
		(fp_poly
			(pts
				(xy -0.5 -1) (xy -0.35 -1) (xy -0.35 -0.7) (xy -0.85 -0.7) (xy -0.85 -0.9) (xy -0.5 -0.9)
			)
			(stroke
				(width 0)
				(type default)
			)
			(fill yes)
			(layer "F.Paste")
		)
		(fp_line
			(start 1.05 -1.2)
			(end 1.05 1.2)
			(stroke
				(width 0.2)
				(type solid)
			)
			(layer "F.CrtYd")
		)
		(fp_line
			(start -1.05 -1.2)
			(end 1.05 -1.2)
			(stroke
				(width 0.2)
				(type solid)
			)
			(layer "F.CrtYd")
		)
		(fp_line
			(start -1.05 -1.2)
			(end -1.05 1.2)
			(stroke
				(width 0.2)
				(type solid)
			)
			(layer "F.CrtYd")
		)
		(fp_line
			(start -1.05 1.2)
			(end 1.05 1.2)
			(stroke
				(width 0.2)
				(type solid)
			)
			(layer "F.CrtYd")
		)
		(fp_line
			(start 1.05 -1.2)
			(end 1.05 1.2)
			(stroke
				(width 0.2)
				(type solid)
			)
			(layer "F.Fab")
		)
		(fp_line
			(start -1.05 -1.2)
			(end 1.05 -1.2)
			(stroke
				(width 0.2)
				(type solid)
			)
			(layer "F.Fab")
		)
		(fp_line
			(start -1.05 -1.2)
			(end -1.05 1.2)
			(stroke
				(width 0.2)
				(type solid)
			)
			(layer "F.Fab")
		)
		(fp_line
			(start 0 -0.5)
			(end 0 0.5)
			(stroke
				(width 0.1)
				(type solid)
			)
			(layer "F.Fab")
		)
		(fp_line
			(start -0.5 0)
			(end 0.5 0)
			(stroke
				(width 0.1)
				(type solid)
			)
			(layer "F.Fab")
		)
		(fp_line
			(start -1.05 1.2)
			(end 1.05 1.2)
			(stroke
				(width 0.2)
				(type solid)
			)
			(layer "F.Fab")
		)
		(fp_text user "${REFERENCE}"
			(at -0.00001 0.09602 90)
			(unlocked yes)
			(layer "F.Fab")
			(effects
				(font
					(face "Arial")
					(size 0.63 0.63)
					(thickness 0.1)
				)
				(justify left bottom)
			)
		)
		(pad "" smd custom
			(at -0.5 -1.1)
			(size 0.000001 0.000001)
			(layers "F.Cu" "F.Mask")
			(solder_mask_margin 0)
			(thermal_bridge_angle 90)
			(options
				(clearance outline)
				(anchor circle)
			)
			(primitives
				(gr_poly
					(pts
						(xy 0 0) (xy 0 -0.15) (xy 0.4 -0.15) (xy 0.4 0.45) (xy 0.2 0.45) (xy 0.2 0)
					)
					(width 0)
					(fill yes)
				)
			)
		)
		(pad "1" smd circle
			(at -0.45 -0.8 90)
			(size 0.18 0.18)
			(layers "F.Cu" "F.Mask" "F.Paste")
			(net "DIP_SW_PPS_SEL")
			(solder_mask_margin 0)
			(solder_paste_margin -1000)
			(thermal_bridge_angle 90)
		)
		(pad "2" smd rect
			(at -0.65 -0.4 90)
			(size 0.6 0.2)
			(layers "F.Cu" "F.Mask" "F.Paste")
			(net "NetR97_2")
			(solder_mask_margin 0)
			(solder_paste_margin -1000)
		)
		(pad "3" smd rect
			(at -0.65 0 90)
			(size 0.6 0.2)
			(layers "F.Cu" "F.Mask" "F.Paste")
			(net "GND")
			(solder_mask_margin 0)
			(solder_paste_margin -1000)
		)
		(pad "4" smd rect
			(at -0.65 0.4 90)
			(size 0.6 0.2)
			(layers "F.Cu" "F.Mask" "F.Paste")
			(net "NetR99_2")
			(solder_mask_margin 0)
			(solder_paste_margin -1000)
		)
		(pad "5" smd rect
			(at -0.65 0.8 90)
			(size 0.6 0.2)
			(layers "F.Cu" "F.Mask" "F.Paste")
			(net "DIP_SW_PPS_SEL")
			(solder_mask_margin 0)
			(solder_paste_margin -1000)
		)
		(pad "6" smd rect
			(at 0 0.8 90)
			(size 0.2 0.6)
			(layers "F.Cu" "F.Mask" "F.Paste")
			(net "GND")
			(solder_mask_margin 0)
			(solder_paste_margin -1000)
		)
		(pad "7" smd rect
			(at 0.65 0.8 90)
			(size 0.6 0.2)
			(layers "F.Cu" "F.Mask" "F.Paste")
			(net "FPGA_MAC_PPS_IN0-")
			(solder_mask_margin 0)
			(solder_paste_margin -1000)
		)
		(pad "8" smd rect
			(at 0.65 0.4 90)
			(size 0.6 0.2)
			(layers "F.Cu" "F.Mask" "F.Paste")
			(net "NetR98_2")
			(solder_mask_margin 0)
			(solder_paste_margin -1000)
		)
		(pad "9" smd rect
			(at 0.65 0 90)
			(size 0.6 0.2)
			(layers "F.Cu" "F.Mask" "F.Paste")
			(net "+3.3V")
			(solder_mask_margin 0)
			(solder_paste_margin -1000)
		)
		(pad "10" smd rect
			(at 0.65 -0.4 90)
			(size 0.6 0.2)
			(layers "F.Cu" "F.Mask" "F.Paste")
			(net "NetR96_2")
			(solder_mask_margin 0)
			(solder_paste_margin -1000)
		)
		(pad "11" smd rect
			(at 0.65 -0.8 90)
			(size 0.6 0.2)
			(layers "F.Cu" "F.Mask" "F.Paste")
			(net "FPGA_MAC_PPS_OUT-")
			(solder_mask_margin 0)
			(solder_paste_margin -1000)
		)
		(pad "12" smd rect
			(at 0 -0.8 90)
			(size 0.2 0.6)
			(layers "F.Cu" "F.Mask" "F.Paste")
			(net "GND")
			(solder_mask_margin 0)
			(solder_paste_margin -1000)
		)
	)
	(footprint "SamacSys:SOP50P310X90-8N"
		(layer "F.Cu")
		(at 82.3761 109.1162 180)
		(property "Reference" "U12"
			(at 0.2286 2.026931 180)
			(unlocked yes)
			(layer "F.SilkS")
			(effects
				(font
					(size 0.762 0.762)
					(thickness 0.2286)
				)
			)
		)
		(property "Value" "NC7WV125K8X"
			(at 6.207715 2.884671 180)
			(unlocked yes)
			(layer "F.SilkS")
			(hide yes)
			(effects
				(font
					(size 0.762 0.762)
					(thickness 0.2286)
				)
			)
		)
		(sheetname "USER_IO")
		(sheetfile "USER_IO.kicad_sch")
		(duplicate_pad_numbers_are_jumpers no)
		(fp_line
			(start 0.8 1)
			(end -0.8 1)
			(stroke
				(width 0.2)
				(type solid)
			)
			(layer "F.SilkS")
		)
		(fp_line
			(start 0.8 -1)
			(end 0.8 1)
			(stroke
				(width 0.2)
				(type solid)
			)
			(layer "F.SilkS")
		)
		(fp_line
			(start 0.8 -1)
			(end -0.8 -1)
			(stroke
				(width 0.2)
				(type solid)
			)
			(layer "F.SilkS")
		)
		(fp_line
			(start -0.8 -1)
			(end -0.8 1)
			(stroke
				(width 0.2)
				(type solid)
			)
			(layer "F.SilkS")
		)
		(fp_line
			(start -1.15 -1.25)
			(end -2 -1.25)
			(stroke
				(width 0.2)
				(type solid)
			)
			(layer "F.SilkS")
		)
		(pad "1" smd rect
			(at -1.575 -0.75 180)
			(size 0.85 0.3)
			(layers "F.Cu" "F.Mask" "F.Paste")
			(net "ANT2_IO_OUT")
		)
		(pad "2" smd rect
			(at -1.575 -0.25 180)
			(size 0.85 0.3)
			(layers "F.Cu" "F.Mask" "F.Paste")
			(net "ANT2_OUT")
		)
		(pad "3" smd rect
			(at -1.575 0.25 180)
			(size 0.85 0.3)
			(layers "F.Cu" "F.Mask" "F.Paste")
			(net "ANT2_IN")
		)
		(pad "4" smd rect
			(at -1.575 0.75 180)
			(size 0.85 0.3)
			(layers "F.Cu" "F.Mask" "F.Paste")
			(net "GND")
		)
		(pad "5" smd rect
			(at 1.575 0.75 180)
			(size 0.85 0.3)
			(layers "F.Cu" "F.Mask" "F.Paste")
			(net "NetR33_1")
		)
		(pad "6" smd rect
			(at 1.575 0.25 180)
			(size 0.85 0.3)
			(layers "F.Cu" "F.Mask" "F.Paste")
			(net "NetR33_1")
		)
		(pad "7" smd rect
			(at 1.575 -0.25 180)
			(size 0.85 0.3)
			(layers "F.Cu" "F.Mask" "F.Paste")
			(net "ANT2_IO_IN")
		)
		(pad "8" smd rect
			(at 1.575 -0.75 180)
			(size 0.85 0.3)
			(layers "F.Cu" "F.Mask" "F.Paste")
			(net "+3.3V")
		)
	)
	(footprint "Vault:RESC1005X40X25LL05T05"
		(layer "F.Cu")
		(at 236.4261 132.9162)
		(property "Reference" "R80"
			(at 2.4286 -0.073079 0)
			(unlocked yes)
			(layer "F.SilkS")
			(effects
				(font
					(size 0.762 0.762)
					(thickness 0.2286)
				)
			)
		)
		(property "Value" "0_1%_0402"
			(at -2.579881 6.66536 270)
			(unlocked yes)
			(layer "F.SilkS")
			(hide yes)
			(effects
				(font
					(size 0.762 0.762)
					(thickness 0.2286)
				)
			)
		)
		(sheetname "POWER")
		(sheetfile "POWER.kicad_sch")
		(duplicate_pad_numbers_are_jumpers no)
		(pad "1" smd rect
			(at -0.4 0 90)
			(size 0.45 0.45)
			(layers "F.Cu" "F.Mask" "F.Paste")
			(net "NetR80_1")
		)
		(pad "2" smd rect
			(at 0.4 0 90)
			(size 0.45 0.45)
			(layers "F.Cu" "F.Mask" "F.Paste")
			(net "+3.3V")
		)
	)
	(footprint "Vault:FP-CC0402-MFG"
		(layer "F.Cu")
		(at 202.2761 121.0662 -90)
		(property "Reference" "C73"
			(at -0.3786 1.423079 90)
			(unlocked yes)
			(layer "F.SilkS")
			(effects
				(font
					(size 0.762 0.762)
					(thickness 0.2286)
				)
			)
		)
		(property "Value" "4.7nF_50V_0402"
			(at -2.592551 9.991575 180)
			(unlocked yes)
			(layer "F.SilkS")
			(hide yes)
			(effects
				(font
					(size 0.762 0.762)
					(thickness 0.2286)
				)
			)
		)
		(sheetname "POWER")
		(sheetfile "POWER.kicad_sch")
		(duplicate_pad_numbers_are_jumpers no)
		(fp_line
			(start 0.51967 0.68067)
			(end -0.53033 0.68067)
			(stroke
				(width 0.2)
				(type solid)
			)
			(layer "F.SilkS")
		)
		(fp_line
			(start 0.525 -0.675)
			(end -0.525 -0.675)
			(stroke
				(width 0.2)
				(type solid)
			)
			(layer "F.SilkS")
		)
		(fp_line
			(start -0.875 0.475)
			(end -0.875 -0.475)
			(stroke
				(width 0.2)
				(type solid)
			)
			(layer "F.CrtYd")
		)
		(fp_line
			(start 0.875 0.475)
			(end -0.875 0.475)
			(stroke
				(width 0.2)
				(type solid)
			)
			(layer "F.CrtYd")
		)
		(fp_line
			(start 0.875 0.475)
			(end 0.875 -0.475)
			(stroke
				(width 0.2)
				(type solid)
			)
			(layer "F.CrtYd")
		)
		(fp_line
			(start 0.875 -0.475)
			(end -0.875 -0.475)
			(stroke
				(width 0.2)
				(type solid)
			)
			(layer "F.CrtYd")
		)
		(fp_line
			(start 0 0.5)
			(end 0 -0.5)
			(stroke
				(width 0.1)
				(type solid)
			)
			(layer "F.Fab")
		)
		(fp_line
			(start -0.875 0.475)
			(end -0.875 -0.475)
			(stroke
				(width 0.2)
				(type solid)
			)
			(layer "F.Fab")
		)
		(fp_line
			(start 0.875 0.475)
			(end -0.875 0.475)
			(stroke
				(width 0.2)
				(type solid)
			)
			(layer "F.Fab")
		)
		(fp_line
			(start 0.875 0.475)
			(end 0.875 -0.475)
			(stroke
				(width 0.2)
				(type solid)
			)
			(layer "F.Fab")
		)
		(fp_line
			(start 0.5 0)
			(end -0.5 0)
			(stroke
				(width 0.1)
				(type solid)
			)
			(layer "F.Fab")
		)
		(fp_line
			(start 0.875 -0.475)
			(end -0.875 -0.475)
			(stroke
				(width 0.2)
				(type solid)
			)
			(layer "F.Fab")
		)
		(fp_text user "${REFERENCE}"
			(at -0.00001 0.09602 270)
			(unlocked yes)
			(layer "F.Fab")
			(effects
				(font
					(face "Arial")
					(size 0.63 0.63)
					(thickness 0.1)
				)
				(justify left bottom)
			)
		)
		(pad "1" smd rect
			(at -0.5 0 270)
			(size 0.5 0.5)
			(layers "F.Cu" "F.Mask" "F.Paste")
			(net "P3V3_SENSE")
			(solder_mask_margin 0)
			(solder_paste_margin 0)
		)
		(pad "2" smd rect
			(at 0.5 0 270)
			(size 0.5 0.5)
			(layers "F.Cu" "F.Mask" "F.Paste")
			(net "P3V3_FB")
			(solder_mask_margin 0)
			(solder_paste_margin 0)
		)
	)
	(footprint "Capacitors:CAPC2012X14N"
		(layer "F.Cu")
		(at 153.9261 80.6162 90)
		(property "Reference" "C62"
			(at 2 1.706655 270)
			(unlocked yes)
			(layer "F.SilkS")
			(effects
				(font
					(size 0.762 0.762)
					(thickness 0.2286)
				)
				(justify left bottom)
			)
		)
		(property "Value" "CAP_0805_10UF_25V"
			(at -2.433445 -1.7875 0)
			(unlocked yes)
			(layer "F.SilkS")
			(hide yes)
			(effects
				(font
					(size 0.762 0.762)
					(thickness 0.2286)
				)
				(justify left bottom)
			)
		)
		(sheetname "MAC")
		(sheetfile "MAC.kicad_sch")
		(duplicate_pad_numbers_are_jumpers no)
		(fp_line
			(start -0.762 -0.9652)
			(end 0.762 -0.9652)
			(stroke
				(width 0.1524)
				(type solid)
			)
			(layer "F.SilkS")
		)
		(fp_line
			(start -0.762 0.9652)
			(end 0.762 0.9652)
			(stroke
				(width 0.1524)
				(type solid)
			)
			(layer "F.SilkS")
		)
		(pad "1" smd rect
			(at -0.9 0 180)
			(size 1.45 1.15)
			(layers "F.Cu" "F.Mask" "F.Paste")
			(net "MAC_VCC")
		)
		(pad "2" smd rect
			(at 0.9 0 180)
			(size 1.45 1.15)
			(layers "F.Cu" "F.Mask" "F.Paste")
			(net "GND")
		)
	)
	(footprint "Vault:FP-ERJ2RK-IPC_A"
		(layer "F.Cu")
		(at 237.4261 137.0162 180)
		(property "Reference" "R1"
			(at -1.6 -0.393345 0)
			(unlocked yes)
			(layer "F.SilkS")
			(effects
				(font
					(size 0.762 0.762)
					(thickness 0.2286)
				)
				(justify left bottom)
			)
		)
		(property "Value" "200_1%_0402"
			(at 19.0909 -11.290235 0)
			(unlocked yes)
			(layer "F.SilkS")
			(hide yes)
			(effects
				(font
					(size 0.762 0.762)
					(thickness 0.2286)
				)
				(justify left bottom)
			)
		)
		(sheetname "POWER")
		(sheetfile "POWER.kicad_sch")
		(duplicate_pad_numbers_are_jumpers no)
		(fp_line
			(start 0.83624 0.73624)
			(end -0.83624 0.73624)
			(stroke
				(width 0.2)
				(type solid)
			)
			(layer "F.SilkS")
		)
		(fp_line
			(start 0.83624 -0.73624)
			(end -0.83624 -0.73624)
			(stroke
				(width 0.2)
				(type solid)
			)
			(layer "F.SilkS")
		)
		(fp_line
			(start 1.03624 0.53624)
			(end -1.03623 0.53624)
			(stroke
				(width 0.2)
				(type solid)
			)
			(layer "F.CrtYd")
		)
		(fp_line
			(start 1.03624 -0.53624)
			(end 1.03624 0.53624)
			(stroke
				(width 0.2)
				(type solid)
			)
			(layer "F.CrtYd")
		)
		(fp_line
			(start 1.03624 -0.53624)
			(end -1.03623 -0.53624)
			(stroke
				(width 0.2)
				(type solid)
			)
			(layer "F.CrtYd")
		)
		(fp_line
			(start -1.03623 -0.53624)
			(end -1.03623 0.53624)
			(stroke
				(width 0.2)
				(type solid)
			)
			(layer "F.CrtYd")
		)
		(fp_line
			(start 1.03624 0.53624)
			(end -1.03623 0.53624)
			(stroke
				(width 0.2)
				(type solid)
			)
			(layer "F.Fab")
		)
		(fp_line
			(start 1.03624 -0.53624)
			(end 1.03624 0.53624)
			(stroke
				(width 0.2)
				(type solid)
			)
			(layer "F.Fab")
		)
		(fp_line
			(start 1.03624 -0.53624)
			(end -1.03623 -0.53624)
			(stroke
				(width 0.2)
				(type solid)
			)
			(layer "F.Fab")
		)
		(fp_line
			(start 0.5 0)
			(end -0.5 0)
			(stroke
				(width 0.1)
				(type solid)
			)
			(layer "F.Fab")
		)
		(fp_line
			(start 0 -0.5)
			(end 0 0.5)
			(stroke
				(width 0.1)
				(type solid)
			)
			(layer "F.Fab")
		)
		(fp_line
			(start -1.03623 -0.53624)
			(end -1.03623 0.53624)
			(stroke
				(width 0.2)
				(type solid)
			)
			(layer "F.Fab")
		)
		(fp_text user "${REFERENCE}"
			(at -0.00001 0.10711 180)
			(unlocked yes)
			(layer "F.Fab")
			(effects
				(font
					(face "Arial")
					(size 0.63 0.63)
					(thickness 0.1)
				)
				(justify left bottom)
			)
		)
		(pad "1" smd rect
			(at -0.50215 0 180)
			(size 0.66818 0.67248)
			(layers "F.Cu" "F.Mask" "F.Paste")
			(net "GND")
			(solder_mask_margin 0)
			(solder_paste_margin 0)
		)
		(pad "2" smd rect
			(at 0.50215 0 180)
			(size 0.66818 0.67248)
			(layers "F.Cu" "F.Mask" "F.Paste")
			(net "NetD4_1")
			(solder_mask_margin 0)
			(solder_paste_margin 0)
		)
	)
	(footprint "Vault:CAPC1608X87X45ML20T05"
		(layer "F.Cu")
		(at 216.9261 66.5162)
		(property "Reference" "C57"
			(at -2.7714 0.126921 0)
			(unlocked yes)
			(layer "F.SilkS")
			(effects
				(font
					(size 0.762 0.762)
					(thickness 0.2286)
				)
			)
		)
		(property "Value" "0.1uF"
			(at 2.069035 2.630671 0)
			(unlocked yes)
			(layer "F.SilkS")
			(hide yes)
			(effects
				(font
					(size 0.762 0.762)
					(thickness 0.2286)
				)
			)
		)
		(sheetname "GPS_IMU_SENSORS")
		(sheetfile "GPS_IMU_SENSORS.kicad_sch")
		(duplicate_pad_numbers_are_jumpers no)
		(pad "1" smd rect
			(at -0.7 0 90)
			(size 1.1 1.05)
			(layers "F.Cu" "F.Mask" "F.Paste")
			(net "GND")
		)
		(pad "2" smd rect
			(at 0.7 0 90)
			(size 1.1 1.05)
			(layers "F.Cu" "F.Mask" "F.Paste")
			(net "+3.3V")
		)
	)
)
